FILE_TYPE = CONNECTIVITY;
{Allegro Design Entry HDL 16.6-p007 (v16-6-112F) 10/10/2012}
"PAGE_NUMBER" = 145;
0"NC";
1"GND\g";
2"GND\g";
3"P3V3_STBY\g";
4"GND\g";
5"GND\g";
6"GND\g";
7"GND\g";
8"GND\g";
9"GND\g";
10"GND\g";
11"GND\g";
12"P2E_SSB_BMC_RX_DN";
13"RST_BMC_SYSRST_BTN_OUT_N";
14"FM_PWR_BTN_N";
15"FM_BMC_PWRBTN_OUT_N";
16"FP_NMI_BTN_N";
17"IRQ_BMC_PCH_NMI_STBY_N";
18"FM_CPU0_PROCHOT_LVT3_BMC_N";
19"IRQ_UV_DETECT_N";
20"FM_BOARD_REV_ID2";
21"FM_CPU_ERR0_LVT3_BMC_N";
22"SP1_BMC_HOST_UART_TX";
23"FM_BATTERY_SENSE_EN_N";
24"IRQ_PVDDQ_KLM_VRHOT_LVT3_N";
25"IRQ_PVCCIN_CPU1_VRHOT_LVC3_N";
26"SMB_LAN_STBY_LVC3_SDA_R";
27"SMB_IE_3V3AUX_SDA";
28"FM_CPU_ERR1_LVT3_BMC_N";
29"FM_MB_SLOT_ID2";
30"FM_MB_SLOT_ID0";
31"RST_SYSTEM_BTN_N";
32"PD_PEREXT";
33"UART_BMC_TXD5";
34"FM_CPU1_PROCHOT_LVT3_BMC_N";
35"IRQ_PVCCIN_CPU0_VRHOT_LVC3_N";
36"IRQ_PVDDQ_ABC_VRHOT_LVT3_N";
37"SP1_BMC_HOST_UART_RX";
38"FM_PMBUS_ALERT_BUF_EN_N";
39"IRQ_OC_DETECT_N";
40"SP2_BMC_CM_UART_RX";
41"SP2_BMC_CM_UART_TX";
42"FM_BMC_CPLD_MP_RST_N";
43"FM_BB_BMC_MP_GPIO";
44"FM_OC_DETECT_EN_N"CDS_PHYS_NET_NAME"FM_OC_DETECT_EN_N"PHYS_NET_NAME"FM_OC_DETECT_EN_N";
45"IRQ_BOARD_BMC_ALERT_N"CDS_PHYS_NET_NAME"IRQ_BOARD_BMC_ALERT_N"PHYS_NET_NAME"IRQ_BOARD_BMC_ALERT_N";
46"FM_CPU1_RC_ERROR_N"CDS_PHYS_NET_NAME"FM_CPU1_RC_ERROR_N"PHYS_NET_NAME"FM_CPU1_RC_ERROR_N";
47"FM_CPU0_RC_ERROR_N";
48"P2E_SSB_BMC_TX_C_DP";
49"P2E_SSB_BMC_TX_C_DN";
50"RST_PLTRST_BUF_N";
51"FM_SSATA_PCIE_M2_SEL";
52"RST_BMC_SRST_N";
53"CLK_24M_25M_BMC_CLKIN";
54"FM_MB_SLOT_ID1";
55"FM_BOARD_REV_ID1";
56"FM_BOARD_REV_ID0";
57"PECI_BMC_R";
58"UART_BMC_RXD5";
59"CLK_100M_BMC_PE_R_DP";
60"CLK_100M_BMC_PE_R_DN";
61"FM_MEM_THERM_EVENT_PCH_N";
62"FM_BIOS_TOP_SWAP";
63"FM_HSC_TIMER_EXP_N";
64"FM_OCP_MEZZC_PRES_N";
65"FM_OCP_MEZZB_PRES_N";
66"FM_OCP_MEZZA_PRES_N";
67"FM_BIOS_SMI_ACTIVE_N";
68"SMB_LAN_STBY_LVC3_SCL_R";
69"SMB_IE_3V3AUX_SCL";
70"H_CPU1_MEMGHJ_MEMHOT_LVT3_BMC_N";
71"FM_BMC_ONCTL_R_N";
72"FM_BMC_FAULT_LED_N";
73"FM_BMC_HEARTBEAT_N";
74"SMB_PCIE_SSD_3V3AUX_SCL";
75"SMB_PCIE_SSD_3V3AUX_SDA";
76"P2E_SSB_BMC_RX_DP";
77"TP_SMB_BUS11_SDA";
78"TP_SMB_BUS11_SCL";
79"PECI_BMC";
80"FM_BMC_ONCTL_R_N";
81"P2E_SSB_BMC_RX_C_DN";
82"P2E_SSB_BMC_RX_C_DP";
83"FM_BMC_ONCTL_N";
84"PU_24M_OSC_OE";
85"CLK_24M_BMC_CLKIN_R";
86"CLK_25M_BMC";
87"CLK_24M_25M_BMC_CLKIN";
%"RES"
"1","(-4750,-250)","0","mstr_discrete","I10";
;
CDS_LIB"mstr_discrete"
ROOM"BMC"
SEC_TYPE"0402"
SEC"1"
BOM_COST"SM_CONTROLLER"
CDS_LOCATION"R9F60"
CDS_SEC"1"
WATTAGE"1/16W"
VALUE"0.0"
LOCATION"R9F60"
TOLERANCE"5%"
PART_NUMBER"G21497-005"
MATERIAL"EMPTY"
PACK_TYPE"0402";
"B"
$PN"2"87;
"A"
$PN"1"86;
%"RES"
"1","(-7450,-2400)","0","mstr_discrete","I100";
;
CDS_SEC"1"
$SEC"1"
CDS_LOCATION"R1T15"
CDS_LIB"mstr_discrete"
PART_NUMBER"G21497-005"
WATTAGE"1/16W"
TOLERANCE"5%"
LOCATION"R1T15"
PACK_TYPE"0402"
MATERIAL"EMPTY"
VALUE"0.0";
"B"
$PN"2"80;
"A"
$PN"1"83;
%"RES"
"1","(-7000,-2650)","5","mstr_discrete","I101";
;
CDS_SEC"1"
$SEC"1"
CDS_LOCATION"R1T23"
CDS_LIB"mstr_discrete"
TOLERANCE"5%"
PACK_TYPE"0402"
VALUE"0.0"
MATERIAL"EMPTY"
LOCATION"R1T23"
WATTAGE"1/16W"
PART_NUMBER"G21497-005";
"B"
$PN"2"1;
"A"
$PN"1"80;
%"GND"
"1","(-7000,-3175)","0","mstr_symbols","I102";
;
CDS_LIB"mstr_symbols"
VOLTAGE"0.0V"
SIZE"1B"
BODY_TYPE"PLUMBING"
HDL_POWER"GND";
"A\NAC"1;
%"RES"
"1","(-4750,-550)","0","mstr_discrete","I11";
;
CDS_LIB"mstr_discrete"
SEC"1"
SEC_TYPE"0402"
ROOM"BMC"
BOM_COST"SM_CONTROLLER"
CDS_LOCATION"R9F62"
CDS_SEC"1"
VALUE"0.0"
TOLERANCE"5%"
LOCATION"R9F62"
PART_NUMBER"G21497-005"
PACK_TYPE"0402"
MATERIAL"CHIP"
WATTAGE"1/16W";
"B"
$PN"2"87;
"A"
$PN"1"85;
%"AST2520A1-GP-GP"
"3","(-3800,-2550)","0","w_hdl","I117";
;
CDS_SEC"3"
$SEC"3"
CDS_LOCATION"U25W4"
PACK_TYPE"ASIC2-GB1"
PART_NUMBER"071.2520A.M001"
CDS_LMAN_SYM_OUTLINE"-1150,1400,1150,-1400"
CDS_LIB"w_hdl"
LOCATION"U25W4"
VALUE"AST2520A1-GP-GP";
"GPIOD5_SD2DAT3"
$PN"E20"20;
"GPIOD6_SD2CD# \B"
$PN"G18"21;
"GPIOL6_TXD1"
$PN"V1"22;
"GPIOF6_TXD4_LHSIRQ# \B"
$PN"G17"23;
"GPIOF4_NDTR4_LHCLK"
$PN"A21"24;
"GPIOF3_NRI4_LHAD3"
$PN"B21"25;
"GPIOL0_NCTS1"
$PN"T2"19;
"GPIOC5_SD1DAT3_SDA12"
$PN"E12"26;
"GPIOC7_SD1WP#_SDA13 \B"
$PN"B11"27;
"GPIOD7_SD2WP# \B"
$PN"C21"28;
"GPIOD2_SD2DAT0"
$PN"F20"29;
"GPIOD0_SD2CLK"
$PN"F19"30;
"GPIOE0_NCTS3"
$PN"B20"31;
"GPIOE1_NDCD3"
$PN"C20"13;
"GPIOE5_NRTS3"
$PN"D19"17;
"PETXP"
$PN"L21"76;
"PETXN"
$PN"L22"12;
"PEREXT"
$PN"K20"32;
"TXD5"
$PN"K1"33;
"GPIOE7_RXD3"
$PN"B19"34;
"GPIOE6_TXD3"
$PN"A20"18;
"GPIOE4_NDTR3"
$PN"E18"16;
"GPIOE3_NRI3"
$PN"F17"15;
"GPIOE2_NDSR3"
$PN"F18"14;
"GPIOF2_NDSR4_LHAD2"
$PN"B22"35;
"GPIOF1_NDCD4_LHAD1"
$PN"J18"0;
"GPIOF0_NCTS4_LHAD0"
$PN"J19"36;
"GPIOL7_RXD1"
$PN"W1"37;
"GPIOL5_NRTS1_VPICLK"
$PN"P3"38;
"GPIOL1_NDCD1_VPIDE"
$PN"T1"39;
"GPIOM7_RXD2_VPIB9"
$PN"T5"40;
"GPIOM6_TXD2_VPIB8"
$PN"R5"41;
"GPIOM5_NRTS2_VPIB7"
$PN"P5"42;
"GPIOM4_NDTR2_VPIB6"
$PN"AA2"43;
"GPIOM3_NRI2_VPIB5"
$PN"Y2"44;
"GPIOM2_NDSR2_VPIB4"
$PN"AA1"45;
"GPIOM1_NDCD2_VPIB3"
$PN"AB2"46;
"GPIOM0_NCTS2_VPIB2"
$PN"Y1"47;
"PERXP"
$PN"M21"48;
"PERXN"
$PN"M22"49;
"PERST# \B"
$PN"L20"50;
"GPIOA3_TIMER4"
$PN"E13"51;
"SRST# \B"
$PN"U18"52;
"CLKIN"
$PN"W18"53;
"GPIOD1_SD2CMD"
$PN"E21"54;
"GPIOD4_SD2DAT2"
$PN"D21"55;
"GPIOD3_SD2DAT1"
$PN"D20"56;
"PECI"
$PN"AB18"57;
"RXD5"
$PN"K2"58;
"PEREFCLKP"
$PN"K21"59;
"PEREFCLKN"
$PN"K22"60;
"GPIOL4_NDTR1_VPIVS"
$PN"P4"61;
"GPIOL3_NRI1_VPIHS"
$PN"U2"62;
"GPIOL2_NDSR1"
$PN"U1"63;
"GPIOF7_RXD4_LHRST# \B"
$PN"H18"64;
"GPIOF5_NRTS4_LHFRAME# \B"
$PN"H19"65;
"GPIOG4_SGPS2CK_SALT1"
$PN"E17"0;
"GPIOG5_SGPS2LD_SALT2"
$PN"D16"0;
"GPIOA2_TIMER3_SPI1CS1# \B"
$PN"D13"66;
"GPIOG7_SGPS2I1_SALT4"
$PN"E14"67;
"GPIOC4_SD1DAT2_SCL12"
$PN"D10"68;
"GPIOC6_SD1CD#_SCL13 \B"
$PN"C11"69;
"GPIOG6_SGPS2I0_SALT3"
$PN"D15"70;
"GPIOY3_SIOONCTRL# \B"
$PN"P21"71;
"GPIOA1_MAC2LINK"
$PN"D14"72;
"GPIOA0_MAC1LINK"
$PN"B14"73;
"GPIOC0_SD1CLK_SCL10"
$PN"C12"74;
"GPIOC1_SD1CMD_SDA10"
$PN"A12"75;
"GPIOC3_SD1DAT1_SDA11"
$PN"D9"77;
"GPIOC2_SD1DAT0_SCL11"
$PN"B12"78;
%"GND"
"1","(-5575,-875)","0","mstr_symbols","I13";
;
CDS_LIB"mstr_symbols"
SIZE"1B"
VOLTAGE"0.0V"
BODY_TYPE"PLUMBING"
HDL_POWER"GND";
"A\NAC"2;
%"RES"
"2","(-7000,-475)","0","mstr_discrete","I14";
;
CDS_LIB"mstr_discrete"
ROOM"BMC"
SEC_TYPE"0402"
BOM_COST"SM_CONTROLLER"
SEC"1"
CDS_LOCATION"R9F61"
CDS_SEC"1"
MATERIAL"CHIP"
PART_NUMBER"G21796-016"
PACK_TYPE"0402"
WATTAGE"1/16W"
TOLERANCE"1%"
VALUE"10.0K"
LOCATION"R9F61";
"A"
$PN"1"3;
"B"
$PN"2"84;
%"CAP_A"
"1","(-7500,-450)","0","dev_discrete","I15";
;
CDS_LIB"dev_discrete"
SEC"1"
CDS_SEC"1"
ROOM"BMC"
SEC_TYPE"0402V"
BOM_COST"SM_CONTROLLER"
CDS_LOCATION"C9F23"
PACK_TYPE"0402V"
VOLTAGE"16V"
TOLERANCE"10%"
MATERIAL"X7R"
PART_NUMBER"A36096-030"
VALUE"0.1UF"
LOCATION"C9F23";
"B"
$PN"2"4;
"A"
$PN"1"3;
%"P3V3_STBY"
"1","(-7500,-200)","0","mstr_symbols","I16";
;
SIZE"1B"
CDS_LIB"mstr_symbols"
VOLTAGE"3.3V"
BODY_TYPE"PLUMBING"
HDL_POWER"P3V3_STBY";
"G\NAC"3;
%"GND"
"1","(-7500,-675)","0","mstr_symbols","I17";
;
SIZE"1B"
VOLTAGE"0.0V"
CDS_LIB"mstr_symbols"
BODY_TYPE"PLUMBING"
HDL_POWER"GND";
"A\NAC"4;
%"RES"
"1","(-5925,-3250)","0","mstr_discrete","I20";
;
CDS_LOCATION"R9F33"
WATTAGE"1/16W"
CDS_LIB"mstr_discrete"
SEC"1"
SEC_TYPE"0402"
ROOM"BMC"
BOM_COST"SM_CONTROLLER"
PACK_TYPE"0402"
CDS_SEC"1"
LOCATION"R9F33"
MATERIAL"CHIP"
VALUE"0.0"
TOLERANCE"5%"
PART_NUMBER"G21497-005";
"B"
$PN"2"57;
"A"
$PN"1"79;
%"RES"
"2","(-7475,-3575)","0","mstr_discrete","I22";
;
CDS_SEC"1"
BOM_COST"SM_CONTROLLER"
SEC"1"
SEC_TYPE"0402"
ROOM"BMC"
CDS_LOCATION"R9F20"
CDS_LIB"mstr_discrete"
PACK_TYPE"0402"
MATERIAL"EMPTY"
WATTAGE"1/16W"
TOLERANCE"1%"
PART_NUMBER"G21796-340"
LOCATION"R9F20"
VALUE"348";
"A"
$PN"1"79;
"B"
$PN"2"5;
%"GND"
"1","(-7475,-3850)","0","mstr_symbols","I23";
;
VOLTAGE"0.0V"
SIZE"1B"
CDS_LIB"mstr_symbols"
BODY_TYPE"PLUMBING"
HDL_POWER"GND";
"A\NAC"5;
%"RES"
"2","(-5450,-4350)","0","mstr_discrete","I30";
;
ROOM"BMC"
BOM_COST"SM_CONTROLLER"
SEC_TYPE"0402"
SEC"1"
CDS_LIB"mstr_discrete"
CDS_SEC"1"
CDS_LOCATION"R25W61"
PART_NUMBER"G21796-010"
MATERIAL"CHIP"
PACK_TYPE"0402"
LOCATION"R25W61"
VALUE"100.0K"
TOLERANCE"1%"
WATTAGE"1/16W";
"A"
$PN"1"59;
"B"
$PN"2"7;
%"RES"
"2","(-5200,-4350)","0","mstr_discrete","I31";
;
CDS_SEC"1"
CDS_LIB"mstr_discrete"
SEC"1"
SEC_TYPE"0402"
BOM_COST"SM_CONTROLLER"
ROOM"BMC"
CDS_LOCATION"R25W62"
PACK_TYPE"0402"
PART_NUMBER"G21796-010"
TOLERANCE"1%"
MATERIAL"CHIP"
LOCATION"R25W62"
VALUE"100.0K"
WATTAGE"1/16W";
"A"
$PN"1"50;
"B"
$PN"2"6;
%"GND"
"1","(-5200,-4700)","0","mstr_symbols","I32";
;
CDS_LIB"mstr_symbols"
VOLTAGE"0.0V"
SIZE"1B"
BODY_TYPE"PLUMBING"
HDL_POWER"GND";
"A\NAC"6;
%"GND"
"1","(-5450,-4700)","0","mstr_symbols","I33";
;
CDS_LIB"mstr_symbols"
VOLTAGE"0.0V"
SIZE"1B"
BODY_TYPE"PLUMBING"
HDL_POWER"GND";
"A\NAC"7;
%"RES"
"2","(-5700,-4350)","0","mstr_discrete","I34";
;
BOM_COST"SM_CONTROLLER"
ROOM"BMC"
SEC_TYPE"0402"
SEC"1"
CDS_LIB"mstr_discrete"
CDS_SEC"1"
CDS_LOCATION"R25W60"
VALUE"100.0K"
WATTAGE"1/16W"
TOLERANCE"1%"
LOCATION"R25W60"
PACK_TYPE"0402"
MATERIAL"CHIP"
PART_NUMBER"G21796-010";
"A"
$PN"1"60;
"B"
$PN"2"8;
%"GND"
"1","(-5700,-4700)","0","mstr_symbols","I35";
;
VOLTAGE"0.0V"
CDS_LIB"mstr_symbols"
SIZE"1B"
BODY_TYPE"PLUMBING"
HDL_POWER"GND";
"A\NAC"8;
%"RES"
"2","(-5950,-4325)","0","mstr_discrete","I36";
;
CDS_SEC"1"
CDS_LIB"mstr_discrete"
SEC_TYPE"0402"
SEC"1"
BOM_COST"SM_CONTROLLER"
ROOM"BMC"
CDS_LOCATION"R25W64"
PACK_TYPE"0402"
LOCATION"R25W64"
VALUE"100.0K"
TOLERANCE"1%"
PART_NUMBER"G21796-010"
WATTAGE"1/16W"
MATERIAL"CHIP";
"A"
$PN"1"48;
"B"
$PN"2"9;
%"GND"
"1","(-5950,-4700)","0","mstr_symbols","I37";
;
CDS_LIB"mstr_symbols"
VOLTAGE"0.0V"
SIZE"1B"
BODY_TYPE"PLUMBING"
HDL_POWER"GND";
"A\NAC"9;
%"RES"
"2","(-6200,-4325)","0","mstr_discrete","I38";
;
CDS_SEC"1"
CDS_LIB"mstr_discrete"
SEC_TYPE"0402"
SEC"1"
BOM_COST"SM_CONTROLLER"
ROOM"BMC"
CDS_LOCATION"R25W65"
VALUE"100.0K"
PACK_TYPE"0402"
PART_NUMBER"G21796-010"
MATERIAL"CHIP"
LOCATION"R25W65"
TOLERANCE"1%"
WATTAGE"1/16W";
"A"
$PN"1"49;
"B"
$PN"2"10;
%"GND"
"1","(-6200,-4700)","0","mstr_symbols","I39";
;
CDS_LIB"mstr_symbols"
VOLTAGE"0.0V"
SIZE"1B"
BODY_TYPE"PLUMBING"
HDL_POWER"GND";
"A\NAC"10;
%"CAP_A"
"2","(-1275,-3700)","0","dev_discrete","I44";
;
CDS_SEC"1"
CDS_LIB"dev_discrete"
ROOM"BMC"
SEC_TYPE"0402V"
SEC"1"
BOM_COST"SM_CONTROLLER"
CDS_LOCATION"C25W21"
PACK_TYPE"0402V"
TOLERANCE"10%"
VALUE"0.1UF"
LOCATION"C25W21"
PART_NUMBER"A36096-030"
VOLTAGE"16V"
MATERIAL"EMPTY";
"A"
$PN"1"12;
"B"
$PN"2"81;
%"CAP_A"
"2","(-1650,-3400)","0","dev_discrete","I45";
;
BOM_COST"SM_CONTROLLER"
SEC"1"
SEC_TYPE"0402V"
ROOM"BMC"
CDS_LIB"dev_discrete"
CDS_SEC"1"
CDS_LOCATION"C25W20"
PART_NUMBER"A36096-030"
PACK_TYPE"0402V"
MATERIAL"EMPTY"
VOLTAGE"16V"
LOCATION"C25W20"
TOLERANCE"10%"
VALUE"0.1UF";
"A"
$PN"1"76;
"B"
$PN"2"82;
%"RES"
"1","(-1325,-3200)","0","mstr_discrete","I46";
;
CDS_SEC"1"
CDS_LIB"mstr_discrete"
ROOM"BMC"
SEC_TYPE"0402"
SEC"1"
BOM_COST"SM_CONTROLLER"
CDS_LOCATION"R25W67"
LOCATION"R25W67"
WATTAGE"1/16W"
PACK_TYPE"0402"
VALUE"10.0K"
TOLERANCE"1%"
MATERIAL"EMPTY"
PART_NUMBER"G21796-016";
"B"
$PN"2"11;
"A"
$PN"1"32;
%"GND"
"1","(-425,-3200)","1","mstr_symbols","I47";
;
SIZE"1B"
CDS_LIB"mstr_symbols"
VOLTAGE"0.0V"
BODY_TYPE"PLUMBING"
HDL_POWER"GND";
"A\NAC"11;
%"OSC_C"
"11","(-6050,-650)","0","mstr_discrete","I8";
;
PACK_TYPE"SM4"
SEC"1"
BOM_COST"SM_CONTROLLER"
SEC_TYPE"SM4"
ROOM"BMC"
CDS_LIB"mstr_discrete"
CDS_LMAN_SYM_OUTLINE"-350,200,350,-200"
CDS_LOCATION"Y9F2"
CDS_SEC"1"
VALUE"24MHZ"
PART_NUMBER"D34520-021"
LOCATION"Y9F2"
MATERIAL"OSC";
"ENABLE_CONTROL"
$PN"1"84;
"VDD"
$PN"4"3;
"GND"
$PN"2"2;
"OUT"
$PN"3"85;
END.
